(kicad_sch
	(version 20250114)
	(generator "eeschema")
	(generator_version "9.0")
	(paper "A3")
	(title_block
		(title "SO-DIMM DDR5 Tester")
		(date "2025-11-26")
		(rev "1.3.0")
		(company "Antmicro Ltd.")
		(comment 1 "www.antmicro.com")
		(comment 2 "Antmicro Ltd")
	)
	(text "Place capacitors close to connector"
		(exclude_from_sim no)
		(at 237.49 99.695 0)
		(effects
			(font
				(size 1.27 1.27)
			)
			(justify left bottom)
		)
	)
	(text "BANK 115"
		(exclude_from_sim no)
		(at 136.525 101.6 0)
		(effects
			(font
				(size 1.27 1.27)
				(thickness 0.4978)
				(bold yes)
			)
			(justify left bottom)
		)
	)
	(text "MGT Interface"
		(exclude_from_sim no)
		(at 14.605 19.05 0)
		(effects
			(font
				(size 2.54 2.54)
				(thickness 0.4978)
				(bold yes)
			)
			(justify left bottom)
		)
	)
	(text "BANK 116"
		(exclude_from_sim no)
		(at 171.45 101.6 0)
		(effects
			(font
				(size 1.27 1.27)
				(thickness 0.4978)
				(bold yes)
			)
			(justify left bottom)
		)
	)
	(no_connect
		(at 186.055 160.655)
	)
	(no_connect
		(at 131.445 145.415)
	)
	(no_connect
		(at 131.445 132.715)
	)
	(no_connect
		(at 131.445 163.195)
	)
	(no_connect
		(at 131.445 112.395)
	)
	(no_connect
		(at 131.445 135.255)
	)
	(no_connect
		(at 131.445 120.015)
	)
	(no_connect
		(at 131.445 140.335)
	)
	(no_connect
		(at 131.445 147.955)
	)
	(no_connect
		(at 131.445 114.935)
	)
	(no_connect
		(at 131.445 150.495)
	)
	(no_connect
		(at 131.445 142.875)
	)
	(no_connect
		(at 131.445 125.095)
	)
	(no_connect
		(at 131.445 137.795)
	)
	(no_connect
		(at 131.445 122.555)
	)
	(no_connect
		(at 131.445 160.655)
	)
	(no_connect
		(at 131.445 158.115)
	)
	(no_connect
		(at 131.445 109.855)
	)
	(no_connect
		(at 131.445 117.475)
	)
	(no_connect
		(at 186.055 163.195)
	)
	(no_connect
		(at 131.445 127.635)
	)
	(no_connect
		(at 131.445 155.575)
	)
	(bus_entry
		(at 278.765 107.315)
		(size 2.54 -2.54)
		(stroke
			(width 0)
			(type default)
		)
	)
	(bus_entry
		(at 278.765 152.4)
		(size 2.54 -2.54)
		(stroke
			(width 0)
			(type default)
		)
	)
	(bus_entry
		(at 278.765 117.475)
		(size 2.54 -2.54)
		(stroke
			(width 0)
			(type default)
		)
	)
	(bus_entry
		(at 278.765 149.86)
		(size 2.54 -2.54)
		(stroke
			(width 0)
			(type default)
		)
	)
	(bus_entry
		(at 278.765 143.51)
		(size 2.54 -2.54)
		(stroke
			(width 0)
			(type default)
		)
	)
	(bus_entry
		(at 278.765 162.56)
		(size 2.54 -2.54)
		(stroke
			(width 0)
			(type default)
		)
	)
	(bus_entry
		(at 278.765 129.54)
		(size 2.54 -2.54)
		(stroke
			(width 0)
			(type default)
		)
	)
	(bus_entry
		(at 278.765 146.05)
		(size 2.54 -2.54)
		(stroke
			(width 0)
			(type default)
		)
	)
	(bus_entry
		(at 278.765 127)
		(size 2.54 -2.54)
		(stroke
			(width 0)
			(type default)
		)
	)
	(bus_entry
		(at 278.765 172.085)
		(size 2.54 -2.54)
		(stroke
			(width 0)
			(type default)
		)
	)
	(bus_entry
		(at 278.765 139.065)
		(size 2.54 -2.54)
		(stroke
			(width 0)
			(type default)
		)
	)
	(bus_entry
		(at 278.765 120.015)
		(size 2.54 -2.54)
		(stroke
			(width 0)
			(type default)
		)
	)
	(bus_entry
		(at 278.765 109.855)
		(size 2.54 -2.54)
		(stroke
			(width 0)
			(type default)
		)
	)
	(bus_entry
		(at 278.765 158.75)
		(size 2.54 -2.54)
		(stroke
			(width 0)
			(type default)
		)
	)
	(bus_entry
		(at 278.765 156.21)
		(size 2.54 -2.54)
		(stroke
			(width 0)
			(type default)
		)
	)
	(bus_entry
		(at 278.765 169.545)
		(size 2.54 -2.54)
		(stroke
			(width 0)
			(type default)
		)
	)
	(bus_entry
		(at 278.765 136.525)
		(size 2.54 -2.54)
		(stroke
			(width 0)
			(type default)
		)
	)
	(bus_entry
		(at 278.765 165.1)
		(size 2.54 -2.54)
		(stroke
			(width 0)
			(type default)
		)
	)
	(wire
		(pts
			(xy 251.46 116.205) (xy 247.65 116.205)
		)
		(stroke
			(width 0)
			(type default)
		)
	)
	(wire
		(pts
			(xy 247.65 170.18) (xy 241.3 170.18)
		)
		(stroke
			(width 0)
			(type default)
		)
	)
	(wire
		(pts
			(xy 247.65 137.16) (xy 241.3 137.16)
		)
		(stroke
			(width 0)
			(type default)
		)
	)
	(wire
		(pts
			(xy 241.3 158.75) (xy 241.3 158.115)
		)
		(stroke
			(width 0)
			(type default)
		)
	)
	(wire
		(pts
			(xy 241.3 156.845) (xy 266.065 156.845)
		)
		(stroke
			(width 0)
			(type default)
		)
	)
	(wire
		(pts
			(xy 225.425 129.54) (xy 241.3 129.54)
		)
		(stroke
			(width 0)
			(type default)
		)
	)
	(wire
		(pts
			(xy 256.54 106.045) (xy 260.35 106.045)
		)
		(stroke
			(width 0)
			(type default)
		)
	)
	(wire
		(pts
			(xy 186.055 135.255) (xy 202.565 135.255)
		)
		(stroke
			(width 0)
			(type default)
		)
	)
	(wire
		(pts
			(xy 186.055 145.415) (xy 202.565 145.415)
		)
		(stroke
			(width 0)
			(type default)
		)
	)
	(wire
		(pts
			(xy 251.46 135.255) (xy 247.65 135.255)
		)
		(stroke
			(width 0)
			(type default)
		)
	)
	(wire
		(pts
			(xy 241.3 152.4) (xy 241.3 151.765)
		)
		(stroke
			(width 0)
			(type default)
		)
	)
	(bus
		(pts
			(xy 281.305 117.475) (xy 281.305 124.46)
		)
		(stroke
			(width 0)
			(type default)
		)
	)
	(wire
		(pts
			(xy 266.065 152.4) (xy 278.765 152.4)
		)
		(stroke
			(width 0)
			(type default)
		)
	)
	(wire
		(pts
			(xy 260.35 128.905) (xy 260.35 130.81)
		)
		(stroke
			(width 0)
			(type default)
		)
	)
	(wire
		(pts
			(xy 186.055 112.395) (xy 202.565 112.395)
		)
		(stroke
			(width 0)
			(type default)
		)
	)
	(wire
		(pts
			(xy 202.565 150.495) (xy 186.055 150.495)
		)
		(stroke
			(width 0)
			(type default)
		)
	)
	(wire
		(pts
			(xy 225.425 117.475) (xy 241.3 117.475)
		)
		(stroke
			(width 0)
			(type default)
		)
	)
	(wire
		(pts
			(xy 251.46 121.285) (xy 247.65 121.285)
		)
		(stroke
			(width 0)
			(type default)
		)
	)
	(wire
		(pts
			(xy 241.3 169.545) (xy 241.3 170.18)
		)
		(stroke
			(width 0)
			(type default)
		)
	)
	(wire
		(pts
			(xy 186.055 117.475) (xy 202.565 117.475)
		)
		(stroke
			(width 0)
			(type default)
		)
	)
	(wire
		(pts
			(xy 260.35 128.905) (xy 266.065 128.905)
		)
		(stroke
			(width 0)
			(type default)
		)
	)
	(wire
		(pts
			(xy 225.425 109.855) (xy 241.3 109.855)
		)
		(stroke
			(width 0)
			(type default)
		)
	)
	(wire
		(pts
			(xy 278.765 162.56) (xy 266.065 162.56)
		)
		(stroke
			(width 0)
			(type default)
		)
	)
	(wire
		(pts
			(xy 266.065 107.95) (xy 266.065 107.315)
		)
		(stroke
			(width 0)
			(type default)
		)
	)
	(bus
		(pts
			(xy 281.305 149.86) (xy 281.305 153.67)
		)
		(stroke
			(width 0)
			(type default)
		)
	)
	(wire
		(pts
			(xy 278.765 107.315) (xy 266.065 107.315)
		)
		(stroke
			(width 0)
			(type default)
		)
	)
	(wire
		(pts
			(xy 251.46 106.045) (xy 247.65 106.045)
		)
		(stroke
			(width 0)
			(type default)
		)
	)
	(bus
		(pts
			(xy 281.305 156.21) (xy 281.305 160.02)
		)
		(stroke
			(width 0)
			(type default)
		)
	)
	(wire
		(pts
			(xy 225.425 139.065) (xy 241.3 139.065)
		)
		(stroke
			(width 0)
			(type default)
		)
	)
	(bus
		(pts
			(xy 281.305 104.775) (xy 281.305 107.315)
		)
		(stroke
			(width 0)
			(type default)
		)
	)
	(wire
		(pts
			(xy 278.765 169.545) (xy 266.065 169.545)
		)
		(stroke
			(width 0)
			(type default)
		)
	)
	(wire
		(pts
			(xy 225.425 165.1) (xy 241.3 165.1)
		)
		(stroke
			(width 0)
			(type default)
		)
	)
	(wire
		(pts
			(xy 202.565 155.575) (xy 186.055 155.575)
		)
		(stroke
			(width 0)
			(type default)
		)
	)
	(wire
		(pts
			(xy 247.65 118.11) (xy 241.3 118.11)
		)
		(stroke
			(width 0)
			(type default)
		)
	)
	(wire
		(pts
			(xy 225.425 127) (xy 241.3 127)
		)
		(stroke
			(width 0)
			(type default)
		)
	)
	(wire
		(pts
			(xy 260.35 106.045) (xy 260.35 107.95)
		)
		(stroke
			(width 0)
			(type default)
		)
	)
	(wire
		(pts
			(xy 225.425 107.315) (xy 241.3 107.315)
		)
		(stroke
			(width 0)
			(type default)
		)
	)
	(wire
		(pts
			(xy 260.35 109.22) (xy 260.35 111.125)
		)
		(stroke
			(width 0)
			(type default)
		)
	)
	(wire
		(pts
			(xy 278.765 117.475) (xy 266.065 117.475)
		)
		(stroke
			(width 0)
			(type default)
		)
	)
	(wire
		(pts
			(xy 247.65 130.81) (xy 247.65 128.905)
		)
		(stroke
			(width 0)
			(type default)
		)
	)
	(wire
		(pts
			(xy 186.055 158.115) (xy 202.565 158.115)
		)
		(stroke
			(width 0)
			(type default)
		)
	)
	(wire
		(pts
			(xy 266.065 139.065) (xy 278.765 139.065)
		)
		(stroke
			(width 0)
			(type default)
		)
	)
	(wire
		(pts
			(xy 256.54 140.335) (xy 260.35 140.335)
		)
		(stroke
			(width 0)
			(type default)
		)
	)
	(wire
		(pts
			(xy 241.3 127) (xy 241.3 127.635)
		)
		(stroke
			(width 0)
			(type default)
		)
	)
	(wire
		(pts
			(xy 186.055 142.875) (xy 202.565 142.875)
		)
		(stroke
			(width 0)
			(type default)
		)
	)
	(wire
		(pts
			(xy 186.055 127.635) (xy 202.565 127.635)
		)
		(stroke
			(width 0)
			(type default)
		)
	)
	(wire
		(pts
			(xy 256.54 135.255) (xy 260.35 135.255)
		)
		(stroke
			(width 0)
			(type default)
		)
	)
	(wire
		(pts
			(xy 278.765 136.525) (xy 266.065 136.525)
		)
		(stroke
			(width 0)
			(type default)
		)
	)
	(wire
		(pts
			(xy 225.425 136.525) (xy 241.3 136.525)
		)
		(stroke
			(width 0)
			(type default)
		)
	)
	(wire
		(pts
			(xy 266.065 146.05) (xy 278.765 146.05)
		)
		(stroke
			(width 0)
			(type default)
		)
	)
	(wire
		(pts
			(xy 241.3 149.86) (xy 241.3 150.495)
		)
		(stroke
			(width 0)
			(type default)
		)
	)
	(wire
		(pts
			(xy 278.765 127) (xy 266.065 127)
		)
		(stroke
			(width 0)
			(type default)
		)
	)
	(wire
		(pts
			(xy 251.46 111.125) (xy 247.65 111.125)
		)
		(stroke
			(width 0)
			(type default)
		)
	)
	(bus
		(pts
			(xy 281.305 107.315) (xy 281.305 114.935)
		)
		(stroke
			(width 0)
			(type default)
		)
	)
	(wire
		(pts
			(xy 260.35 171.45) (xy 260.35 173.355)
		)
		(stroke
			(width 0)
			(type default)
		)
	)
	(wire
		(pts
			(xy 266.065 170.18) (xy 266.065 169.545)
		)
		(stroke
			(width 0)
			(type default)
		)
	)
	(wire
		(pts
			(xy 251.46 125.73) (xy 247.65 125.73)
		)
		(stroke
			(width 0)
			(type default)
		)
	)
	(wire
		(pts
			(xy 247.65 140.335) (xy 247.65 138.43)
		)
		(stroke
			(width 0)
			(type default)
		)
	)
	(wire
		(pts
			(xy 186.055 122.555) (xy 202.565 122.555)
		)
		(stroke
			(width 0)
			(type default)
		)
	)
	(wire
		(pts
			(xy 186.055 109.855) (xy 202.565 109.855)
		)
		(stroke
			(width 0)
			(type default)
		)
	)
	(wire
		(pts
			(xy 247.65 168.275) (xy 247.65 170.18)
		)
		(stroke
			(width 0)
			(type default)
		)
	)
	(wire
		(pts
			(xy 256.54 173.355) (xy 260.35 173.355)
		)
		(stroke
			(width 0)
			(type default)
		)
	)
	(wire
		(pts
			(xy 260.35 116.205) (xy 260.35 118.11)
		)
		(stroke
			(width 0)
			(type default)
		)
	)
	(wire
		(pts
			(xy 241.3 162.56) (xy 241.3 163.195)
		)
		(stroke
			(width 0)
			(type default)
		)
	)
	(wire
		(pts
			(xy 260.35 107.95) (xy 266.065 107.95)
		)
		(stroke
			(width 0)
			(type default)
		)
	)
	(wire
		(pts
			(xy 256.54 116.205) (xy 260.35 116.205)
		)
		(stroke
			(width 0)
			(type default)
		)
	)
	(wire
		(pts
			(xy 186.055 140.335) (xy 202.565 140.335)
		)
		(stroke
			(width 0)
			(type default)
		)
	)
	(wire
		(pts
			(xy 247.65 107.95) (xy 241.3 107.95)
		)
		(stroke
			(width 0)
			(type default)
		)
	)
	(bus
		(pts
			(xy 281.305 167.005) (xy 281.305 169.545)
		)
		(stroke
			(width 0)
			(type default)
		)
	)
	(wire
		(pts
			(xy 260.35 170.18) (xy 266.065 170.18)
		)
		(stroke
			(width 0)
			(type default)
		)
	)
	(wire
		(pts
			(xy 266.065 118.11) (xy 266.065 117.475)
		)
		(stroke
			(width 0)
			(type default)
		)
	)
	(wire
		(pts
			(xy 241.3 117.475) (xy 241.3 118.11)
		)
		(stroke
			(width 0)
			(type default)
		)
	)
	(wire
		(pts
			(xy 186.055 125.095) (xy 202.565 125.095)
		)
		(stroke
			(width 0)
			(type default)
		)
	)
	(wire
		(pts
			(xy 266.065 145.415) (xy 266.065 146.05)
		)
		(stroke
			(width 0)
			(type default)
		)
	)
	(wire
		(pts
			(xy 241.3 163.195) (xy 266.065 163.195)
		)
		(stroke
			(width 0)
			(type default)
		)
	)
	(wire
		(pts
			(xy 278.765 156.21) (xy 266.065 156.21)
		)
		(stroke
			(width 0)
			(type default)
		)
	)
	(wire
		(pts
			(xy 251.46 173.355) (xy 247.65 173.355)
		)
		(stroke
			(width 0)
			(type default)
		)
	)
	(bus
		(pts
			(xy 281.305 103.505) (xy 281.305 104.775)
		)
		(stroke
			(width 0)
			(type default)
		)
	)
	(wire
		(pts
			(xy 241.3 156.21) (xy 241.3 156.845)
		)
		(stroke
			(width 0)
			(type default)
		)
	)
	(wire
		(pts
			(xy 260.35 119.38) (xy 266.065 119.38)
		)
		(stroke
			(width 0)
			(type default)
		)
	)
	(wire
		(pts
			(xy 247.65 173.355) (xy 247.65 171.45)
		)
		(stroke
			(width 0)
			(type default)
		)
	)
	(wire
		(pts
			(xy 241.3 172.085) (xy 241.3 171.45)
		)
		(stroke
			(width 0)
			(type default)
		)
	)
	(wire
		(pts
			(xy 247.65 135.255) (xy 247.65 137.16)
		)
		(stroke
			(width 0)
			(type default)
		)
	)
	(wire
		(pts
			(xy 260.35 137.16) (xy 266.065 137.16)
		)
		(stroke
			(width 0)
			(type default)
		)
	)
	(wire
		(pts
			(xy 241.3 165.1) (xy 241.3 164.465)
		)
		(stroke
			(width 0)
			(type default)
		)
	)
	(bus
		(pts
			(xy 281.305 133.985) (xy 281.305 136.525)
		)
		(stroke
			(width 0)
			(type default)
		)
	)
	(wire
		(pts
			(xy 266.065 164.465) (xy 266.065 165.1)
		)
		(stroke
			(width 0)
			(type default)
		)
	)
	(wire
		(pts
			(xy 278.765 143.51) (xy 266.065 143.51)
		)
		(stroke
			(width 0)
			(type default)
		)
	)
	(wire
		(pts
			(xy 260.35 109.22) (xy 266.065 109.22)
		)
		(stroke
			(width 0)
			(type default)
		)
	)
	(wire
		(pts
			(xy 241.3 150.495) (xy 266.065 150.495)
		)
		(stroke
			(width 0)
			(type default)
		)
	)
	(bus
		(pts
			(xy 281.305 127) (xy 281.305 133.985)
		)
		(stroke
			(width 0)
			(type default)
		)
	)
	(wire
		(pts
			(xy 225.425 146.05) (xy 241.3 146.05)
		)
		(stroke
			(width 0)
			(type default)
		)
	)
	(wire
		(pts
			(xy 256.54 168.275) (xy 260.35 168.275)
		)
		(stroke
			(width 0)
			(type default)
		)
	)
	(wire
		(pts
			(xy 241.3 120.015) (xy 241.3 119.38)
		)
		(stroke
			(width 0)
			(type default)
		)
	)
	(wire
		(pts
			(xy 260.35 119.38) (xy 260.35 121.285)
		)
		(stroke
			(width 0)
			(type default)
		)
	)
	(wire
		(pts
			(xy 225.425 169.545) (xy 241.3 169.545)
		)
		(stroke
			(width 0)
			(type default)
		)
	)
	(wire
		(pts
			(xy 266.065 172.085) (xy 278.765 172.085)
		)
		(stroke
			(width 0)
			(type default)
		)
	)
	(bus
		(pts
			(xy 281.305 143.51) (xy 281.305 147.32)
		)
		(stroke
			(width 0)
			(type default)
		)
	)
	(bus
		(pts
			(xy 283.845 102.87) (xy 281.94 102.87)
		)
		(stroke
			(width 0)
			(type default)
		)
	)
	(wire
		(pts
			(xy 266.065 144.145) (xy 266.065 143.51)
		)
		(stroke
			(width 0)
			(type default)
		)
	)
	(wire
		(pts
			(xy 241.3 107.315) (xy 241.3 107.95)
		)
		(stroke
			(width 0)
			(type default)
		)
	)
	(wire
		(pts
			(xy 266.065 129.54) (xy 278.765 129.54)
		)
		(stroke
			(width 0)
			(type default)
		)
	)
	(wire
		(pts
			(xy 241.3 143.51) (xy 241.3 144.145)
		)
		(stroke
			(width 0)
			(type default)
		)
	)
	(wire
		(pts
			(xy 241.3 151.765) (xy 266.065 151.765)
		)
		(stroke
			(width 0)
			(type default)
		)
	)
	(wire
		(pts
			(xy 241.3 129.54) (xy 241.3 128.905)
		)
		(stroke
			(width 0)
			(type default)
		)
	)
	(wire
		(pts
			(xy 186.055 137.795) (xy 202.565 137.795)
		)
		(stroke
			(width 0)
			(type default)
		)
	)
	(wire
		(pts
			(xy 241.3 145.415) (xy 266.065 145.415)
		)
		(stroke
			(width 0)
			(type default)
		)
	)
	(wire
		(pts
			(xy 266.065 156.845) (xy 266.065 156.21)
		)
		(stroke
			(width 0)
			(type default)
		)
	)
	(wire
		(pts
			(xy 266.065 109.855) (xy 278.765 109.855)
		)
		(stroke
			(width 0)
			(type default)
		)
	)
	(bus
		(pts
			(xy 281.305 153.67) (xy 281.305 156.21)
		)
		(stroke
			(width 0)
			(type default)
		)
	)
	(wire
		(pts
			(xy 247.65 121.285) (xy 247.65 119.38)
		)
		(stroke
			(width 0)
			(type default)
		)
	)
	(wire
		(pts
			(xy 251.46 168.275) (xy 247.65 168.275)
		)
		(stroke
			(width 0)
			(type default)
		)
	)
	(wire
		(pts
			(xy 241.3 171.45) (xy 247.65 171.45)
		)
		(stroke
			(width 0)
			(type default)
		)
	)
	(wire
		(pts
			(xy 260.35 138.43) (xy 260.35 140.335)
		)
		(stroke
			(width 0)
			(type default)
		)
	)
	(wire
		(pts
			(xy 260.35 125.73) (xy 260.35 127.635)
		)
		(stroke
			(width 0)
			(type default)
		)
	)
	(wire
		(pts
			(xy 247.65 125.73) (xy 247.65 127.635)
		)
		(stroke
			(width 0)
			(type default)
		)
	)
	(wire
		(pts
			(xy 225.425 172.085) (xy 241.3 172.085)
		)
		(stroke
			(width 0)
			(type default)
		)
	)
	(wire
		(pts
			(xy 247.65 127.635) (xy 241.3 127.635)
		)
		(stroke
			(width 0)
			(type default)
		)
	)
	(bus
		(pts
			(xy 281.94 102.87) (xy 281.305 103.505)
		)
		(stroke
			(width 0)
			(type default)
		)
	)
	(wire
		(pts
			(xy 266.065 158.115) (xy 266.065 158.75)
		)
		(stroke
			(width 0)
			(type default)
		)
	)
	(wire
		(pts
			(xy 241.3 109.22) (xy 247.65 109.22)
		)
		(stroke
			(width 0)
			(type default)
		)
	)
	(bus
		(pts
			(xy 281.305 140.97) (xy 281.305 143.51)
		)
		(stroke
			(width 0)
			(type default)
		)
	)
	(wire
		(pts
			(xy 225.425 162.56) (xy 241.3 162.56)
		)
		(stroke
			(width 0)
			(type default)
		)
	)
	(bus
		(pts
			(xy 281.305 162.56) (xy 281.305 167.005)
		)
		(stroke
			(width 0)
			(type default)
		)
	)
	(wire
		(pts
			(xy 266.065 138.43) (xy 266.065 139.065)
		)
		(stroke
			(width 0)
			(type default)
		)
	)
	(wire
		(pts
			(xy 241.3 144.145) (xy 266.065 144.145)
		)
		(stroke
			(width 0)
			(type default)
		)
	)
	(wire
		(pts
			(xy 241.3 164.465) (xy 266.065 164.465)
		)
		(stroke
			(width 0)
			(type default)
		)
	)
	(wire
		(pts
			(xy 260.35 118.11) (xy 266.065 118.11)
		)
		(stroke
			(width 0)
			(type default)
		)
	)
	(wire
		(pts
			(xy 241.3 119.38) (xy 247.65 119.38)
		)
		(stroke
			(width 0)
			(type default)
		)
	)
	(wire
		(pts
			(xy 247.65 111.125) (xy 247.65 109.22)
		)
		(stroke
			(width 0)
			(type default)
		)
	)
	(wire
		(pts
			(xy 247.65 106.045) (xy 247.65 107.95)
		)
		(stroke
			(width 0)
			(type default)
		)
	)
	(wire
		(pts
			(xy 256.54 130.81) (xy 260.35 130.81)
		)
		(stroke
			(width 0)
			(type default)
		)
	)
	(bus
		(pts
			(xy 281.305 160.02) (xy 281.305 162.56)
		)
		(stroke
			(width 0)
			(type default)
		)
	)
	(wire
		(pts
			(xy 266.065 120.015) (xy 278.765 120.015)
		)
		(stroke
			(width 0)
			(type default)
		)
	)
	(wire
		(pts
			(xy 225.425 158.75) (xy 241.3 158.75)
		)
		(stroke
			(width 0)
			(type default)
		)
	)
	(wire
		(pts
			(xy 266.065 137.16) (xy 266.065 136.525)
		)
		(stroke
			(width 0)
			(type default)
		)
	)
	(wire
		(pts
			(xy 241.3 136.525) (xy 241.3 137.16)
		)
		(stroke
			(width 0)
			(type default)
		)
	)
	(wire
		(pts
			(xy 266.065 158.75) (xy 278.765 158.75)
		)
		(stroke
			(width 0)
			(type default)
		)
	)
	(wire
		(pts
			(xy 260.35 138.43) (xy 266.065 138.43)
		)
		(stroke
			(width 0)
			(type default)
		)
	)
	(wire
		(pts
			(xy 251.46 130.81) (xy 247.65 130.81)
		)
		(stroke
			(width 0)
			(type default)
		)
	)
	(wire
		(pts
			(xy 266.065 127.635) (xy 266.065 127)
		)
		(stroke
			(width 0)
			(type default)
		)
	)
	(bus
		(pts
			(xy 281.305 136.525) (xy 281.305 140.97)
		)
		(stroke
			(width 0)
			(type default)
		)
	)
	(wire
		(pts
			(xy 266.065 165.1) (xy 278.765 165.1)
		)
		(stroke
			(width 0)
			(type default)
		)
	)
	(wire
		(pts
			(xy 266.065 128.905) (xy 266.065 129.54)
		)
		(stroke
			(width 0)
			(type default)
		)
	)
	(wire
		(pts
			(xy 256.54 121.285) (xy 260.35 121.285)
		)
		(stroke
			(width 0)
			(type default)
		)
	)
	(wire
		(pts
			(xy 225.425 149.86) (xy 241.3 149.86)
		)
		(stroke
			(width 0)
			(type default)
		)
	)
	(wire
		(pts
			(xy 266.065 171.45) (xy 266.065 172.085)
		)
		(stroke
			(width 0)
			(type default)
		)
	)
	(wire
		(pts
			(xy 266.065 150.495) (xy 266.065 149.86)
		)
		(stroke
			(width 0)
			(type default)
		)
	)
	(wire
		(pts
			(xy 256.54 111.125) (xy 260.35 111.125)
		)
		(stroke
			(width 0)
			(type default)
		)
	)
	(wire
		(pts
			(xy 225.425 152.4) (xy 241.3 152.4)
		)
		(stroke
			(width 0)
			(type default)
		)
	)
	(wire
		(pts
			(xy 266.065 109.22) (xy 266.065 109.855)
		)
		(stroke
			(width 0)
			(type default)
		)
	)
	(wire
		(pts
			(xy 260.35 135.255) (xy 260.35 137.16)
		)
		(stroke
			(width 0)
			(type default)
		)
	)
	(wire
		(pts
			(xy 186.055 120.015) (xy 202.565 120.015)
		)
		(stroke
			(width 0)
			(type default)
		)
	)
	(wire
		(pts
			(xy 186.055 132.715) (xy 202.565 132.715)
		)
		(stroke
			(width 0)
			(type default)
		)
	)
	(wire
		(pts
			(xy 241.3 139.065) (xy 241.3 138.43)
		)
		(stroke
			(width 0)
			(type default)
		)
	)
	(bus
		(pts
			(xy 281.305 147.32) (xy 281.305 149.86)
		)
		(stroke
			(width 0)
			(type default)
		)
	)
	(wire
		(pts
			(xy 241.3 146.05) (xy 241.3 145.415)
		)
		(stroke
			(width 0)
			(type default)
		)
	)
	(wire
		(pts
			(xy 225.425 120.015) (xy 241.3 120.015)
		)
		(stroke
			(width 0)
			(type default)
		)
	)
	(wire
		(pts
			(xy 247.65 116.205) (xy 247.65 118.11)
		)
		(stroke
			(width 0)
			(type default)
		)
	)
	(wire
		(pts
			(xy 260.35 127.635) (xy 266.065 127.635)
		)
		(stroke
			(width 0)
			(type default)
		)
	)
	(bus
		(pts
			(xy 281.305 114.935) (xy 281.305 117.475)
		)
		(stroke
			(width 0)
			(type default)
		)
	)
	(wire
		(pts
			(xy 278.765 149.86) (xy 266.065 149.86)
		)
		(stroke
			(width 0)
			(type default)
		)
	)
	(wire
		(pts
			(xy 260.35 171.45) (xy 266.065 171.45)
		)
		(stroke
			(width 0)
			(type default)
		)
	)
	(wire
		(pts
			(xy 251.46 140.335) (xy 247.65 140.335)
		)
		(stroke
			(width 0)
			(type default)
		)
	)
	(wire
		(pts
			(xy 266.065 163.195) (xy 266.065 162.56)
		)
		(stroke
			(width 0)
			(type default)
		)
	)
	(wire
		(pts
			(xy 256.54 125.73) (xy 260.35 125.73)
		)
		(stroke
			(width 0)
			(type default)
		)
	)
	(wire
		(pts
			(xy 241.3 128.905) (xy 247.65 128.905)
		)
		(stroke
			(width 0)
			(type default)
		)
	)
	(wire
		(pts
			(xy 241.3 158.115) (xy 266.065 158.115)
		)
		(stroke
			(width 0)
			(type default)
		)
	)
	(wire
		(pts
			(xy 266.065 151.765) (xy 266.065 152.4)
		)
		(stroke
			(width 0)
			(type default)
		)
	)
	(bus
		(pts
			(xy 281.305 124.46) (xy 281.305 127)
		)
		(stroke
			(width 0)
			(type default)
		)
	)
	(wire
		(pts
			(xy 241.3 138.43) (xy 247.65 138.43)
		)
		(stroke
			(width 0)
			(type default)
		)
	)
	(wire
		(pts
			(xy 266.065 119.38) (xy 266.065 120.015)
		)
		(stroke
			(width 0)
			(type default)
		)
	)
	(wire
		(pts
			(xy 225.425 156.21) (xy 241.3 156.21)
		)
		(stroke
			(width 0)
			(type default)
		)
	)
	(wire
		(pts
			(xy 225.425 143.51) (xy 241.3 143.51)
		)
		(stroke
			(width 0)
			(type default)
		)
	)
	(wire
		(pts
			(xy 260.35 168.275) (xy 260.35 170.18)
		)
		(stroke
			(width 0)
			(type default)
		)
	)
	(wire
		(pts
			(xy 186.055 147.955) (xy 202.565 147.955)
		)
		(stroke
			(width 0)
			(type default)
		)
	)
	(wire
		(pts
			(xy 241.3 109.855) (xy 241.3 109.22)
		)
		(stroke
			(width 0)
			(type default)
		)
	)
	(wire
		(pts
			(xy 186.055 114.935) (xy 202.565 114.935)
		)
		(stroke
			(width 0)
			(type default)
		)
	)
	(label "GTX_TX3_P"
		(at 225.425 136.525 0)
		(effects
			(font
				(size 1.27 1.27)
			)
			(justify left bottom)
		)
	)
	(label "GTX_TX3_N"
		(at 225.425 139.065 0)
		(effects
			(font
				(size 1.27 1.27)
			)
			(justify left bottom)
		)
	)
	(label "PCIE.TXD2_N"
		(at 278.765 120.015 180)
		(effects
			(font
				(size 1.27 1.27)
			)
			(justify right bottom)
		)
	)
	(label "PCIE.TXD2_P"
		(at 278.765 117.475 180)
		(effects
			(font
				(size 1.27 1.27)
			)
			(justify right bottom)
		)
	)
	(label "PCIE.TXD0_N"
		(at 278.765 139.065 180)
		(effects
			(font
				(size 1.27 1.27)
			)
			(justify right bottom)
		)
	)
	(label "GTX_RX2_N"
		(at 225.425 158.75 0)
		(effects
			(font
				(size 1.27 1.27)
			)
			(justify left bottom)
		)
	)
	(label "GTX_TX1_N"
		(at 202.565 117.475 180)
		(effects
			(font
				(size 1.27 1.27)
			)
			(justify right bottom)
		)
	)
	(label "GTR_REFCLK0_N"
		(at 225.425 172.085 0)
		(effects
			(font
				(size 1.27 1.27)
			)
			(justify left bottom)
		)
	)
	(label "GTX_RX1_N"
		(at 202.565 140.335 180)
		(effects
			(font
				(size 1.27 1.27)
			)
			(justify right bottom)
		)
	)
	(label "GTX_TX0_P"
		(at 202.565 109.855 180)
		(effects
			(font
				(size 1.27 1.27)
			)
			(justify right bottom)
		)
	)
	(label "GTX_RX0_N"
		(at 225.425 146.05 0)
		(effects
			(font
				(size 1.27 1.27)
			)
			(justify left bottom)
		)
	)
	(label "GTX_RX0_P"
		(at 225.425 143.51 0)
		(effects
			(font
				(size 1.27 1.27)
			)
			(justify left bottom)
		)
	)
	(label "GTX_TX3_N"
		(at 202.565 127.635 180)
		(effects
			(font
				(size 1.27 1.27)
			)
			(justify right bottom)
		)
	)
	(label "PCIE.RXD3_P"
		(at 278.765 143.51 180)
		(effects
			(font
				(size 1.27 1.27)
			)
			(justify right bottom)
		)
	)
	(label "GTX_RX2_P"
		(at 202.565 142.875 180)
		(effects
			(font
				(size 1.27 1.27)
			)
			(justify right bottom)
		)
	)
	(label "PCIE.CLK_N"
		(at 278.765 172.085 180)
		(effects
			(font
				(size 1.27 1.27)
			)
			(justify right bottom)
		)
	)
	(label "PCIE.RXD0_N"
		(at 278.765 165.1 180)
		(effects
			(font
				(size 1.27 1.27)
			)
			(justify right bottom)
		)
	)
	(label "PCIE.RXD0_P"
		(at 278.765 162.56 180)
		(effects
			(font
				(size 1.27 1.27)
			)
			(justify right bottom)
		)
	)
	(label "GTX_TX2_P"
		(at 225.425 127 0)
		(effects
			(font
				(size 1.27 1.27)
			)
			(justify left bottom)
		)
	)
	(label "GTX_RX3_N"
		(at 225.425 165.1 0)
		(effects
			(font
				(size 1.27 1.27)
			)
			(justify left bottom)
		)
	)
	(label "GTX_TX2_P"
		(at 202.565 120.015 180)
		(effects
			(font
				(size 1.27 1.27)
			)
			(justify right bottom)
		)
	)
	(label "PCIE.TXD3_N"
		(at 278.765 109.855 180)
		(effects
			(font
				(size 1.27 1.27)
			)
			(justify right bottom)
		)
	)
	(label "GTX_RX3_N"
		(at 202.565 150.495 180)
		(effects
			(font
				(size 1.27 1.27)
			)
			(justify right bottom)
		)
	)
	(label "PCIE.RXD3_N"
		(at 278.765 146.05 180)
		(effects
			(font
				(size 1.27 1.27)
			)
			(justify right bottom)
		)
	)
	(label "GTX_TX0_N"
		(at 202.565 112.395 180)
		(effects
			(font
				(size 1.27 1.27)
			)
			(justify right bottom)
		)
	)
	(label "GTX_RX3_P"
		(at 202.565 147.955 180)
		(effects
			(font
				(size 1.27 1.27)
			)
			(justify right bottom)
		)
	)
	(label "GTX_RX3_P"
		(at 225.425 162.56 0)
		(effects
			(font
				(size 1.27 1.27)
			)
			(justify left bottom)
		)
	)
	(label "GTR_REFCLK0_P"
		(at 225.425 169.545 0)
		(effects
			(font
				(size 1.27 1.27)
			)
			(justify left bottom)
		)
	)
	(label "GTX_RX2_P"
		(at 225.425 156.21 0)
		(effects
			(font
				(size 1.27 1.27)
			)
			(justify left bottom)
		)
	)
	(label "GTX_TX3_P"
		(at 202.565 125.095 180)
		(effects
			(font
				(size 1.27 1.27)
			)
			(justify right bottom)
		)
	)
	(label "PCIE.TXD1_P"
		(at 278.765 127 180)
		(effects
			(font
				(size 1.27 1.27)
			)
			(justify right bottom)
		)
	)
	(label "GTX_TX0_N"
		(at 225.425 109.855 0)
		(effects
			(font
				(size 1.27 1.27)
			)
			(justify left bottom)
		)
	)
	(label "GTX_RX0_N"
		(at 202.565 135.255 180)
		(effects
			(font
				(size 1.27 1.27)
			)
			(justify right bottom)
		)
	)
	(label "GTX_TX2_N"
		(at 202.565 122.555 180)
		(effects
			(font
				(size 1.27 1.27)
			)
			(justify right bottom)
		)
	)
	(label "PCIE.TXD3_P"
		(at 278.765 107.315 180)
		(effects
			(font
				(size 1.27 1.27)
			)
			(justify right bottom)
		)
	)
	(label "GTX_TX1_P"
		(at 202.565 114.935 180)
		(effects
			(font
				(size 1.27 1.27)
			)
			(justify right bottom)
		)
	)
	(label "GTX_RX1_P"
		(at 202.565 137.795 180)
		(effects
			(font
				(size 1.27 1.27)
			)
			(justify right bottom)
		)
	)
	(label "GTX_RX1_P"
		(at 225.425 149.86 0)
		(effects
			(font
				(size 1.27 1.27)
			)
			(justify left bottom)
		)
	)
	(label "GTX_TX1_P"
		(at 225.425 117.475 0)
		(effects
			(font
				(size 1.27 1.27)
			)
			(justify left bottom)
		)
	)
	(label "GTX_RX2_N"
		(at 202.565 145.415 180)
		(effects
			(font
				(size 1.27 1.27)
			)
			(justify right bottom)
		)
	)
	(label "PCIE.RXD2_P"
		(at 278.765 149.86 180)
		(effects
			(font
				(size 1.27 1.27)
			)
			(justify right bottom)
		)
	)
	(label "PCIE.CLK_P"
		(at 278.765 169.545 180)
		(effects
			(font
				(size 1.27 1.27)
			)
			(justify right bottom)
		)
	)
	(label "GTR_REFCLK0_P"
		(at 202.565 155.575 180)
		(effects
			(font
				(size 1.27 1.27)
			)
			(justify right bottom)
		)
	)
	(label "PCIE.TXD1_N"
		(at 278.765 129.54 180)
		(effects
			(font
				(size 1.27 1.27)
			)
			(justify right bottom)
		)
	)
	(label "GTX_TX1_N"
		(at 225.425 120.015 0)
		(effects
			(font
				(size 1.27 1.27)
			)
			(justify left bottom)
		)
	)
	(label "PCIE.RXD1_N"
		(at 278.765 158.75 180)
		(effects
			(font
				(size 1.27 1.27)
			)
			(justify right bottom)
		)
	)
	(label "PCIE.TXD0_P"
		(at 278.765 136.525 180)
		(effects
			(font
				(size 1.27 1.27)
			)
			(justify right bottom)
		)
	)
	(label "GTX_TX2_N"
		(at 225.425 129.54 0)
		(effects
			(font
				(size 1.27 1.27)
			)
			(justify left bottom)
		)
	)
	(label "GTX_TX0_P"
		(at 225.425 107.315 0)
		(effects
			(font
				(size 1.27 1.27)
			)
			(justify left bottom)
		)
	)
	(label "GTR_REFCLK0_N"
		(at 202.565 158.115 180)
		(effects
			(font
				(size 1.27 1.27)
			)
			(justify right bottom)
		)
	)
	(label "PCIE.RXD2_N"
		(at 278.765 152.4 180)
		(effects
			(font
				(size 1.27 1.27)
			)
			(justify right bottom)
		)
	)
	(label "GTX_RX0_P"
		(at 202.565 132.715 180)
		(effects
			(font
				(size 1.27 1.27)
			)
			(justify right bottom)
		)
	)
	(label "PCIE.RXD1_P"
		(at 278.765 156.21 180)
		(effects
			(font
				(size 1.27 1.27)
			)
			(justify right bottom)
		)
	)
	(label "GTX_RX1_N"
		(at 225.425 152.4 0)
		(effects
			(font
				(size 1.27 1.27)
			)
			(justify left bottom)
		)
	)
	(hierarchical_label "PCIE{PCIe_x4}"
		(shape bidirectional)
		(at 283.845 102.87 0)
		(effects
			(font
				(size 1.27 1.27)
			)
			(justify left)
		)
	)
	(symbol
		(lib_id "antmicroCapacitors0402:C_100n_0402")
		(at 256.54 116.205 0)
		(mirror y)
		(unit 1)
		(exclude_from_sim no)
		(in_bom yes)
		(on_board yes)
		(dnp no)
		(property "Reference" "C227"
			(at 257.81 114.935 0)
			(effects
				(font
					(size 1.27 1.27)
				)
			)
		)
		(property "Value" "C_100n_0402"
			(at 236.22 126.365 0)
			(effects
				(font
					(size 1.27 1.27)
					(thickness 0.15)
				)
				(justify left bottom)
				(hide yes)
			)
		)
		(property "Footprint" "antmicro-footprints:C_0402_1005Metric"
			(at 236.22 128.905 0)
			(effects
				(font
					(size 1.27 1.27)
					(thickness 0.15)
				)
				(justify left bottom)
				(hide yes)
			)
		)
		(property "Datasheet" "https://www.murata.com/products/productdetail?partno=GRM155R61H104KE14%23"
			(at 236.22 131.445 0)
			(effects
				(font
					(size 1.27 1.27)
					(thickness 0.15)
				)
				(justify left bottom)
				(hide yes)
			)
		)
		(property "Description" ""
			(at 256.54 116.205 0)
			(effects
				(font
					(size 1.27 1.27)
				)
			)
		)
		(property "Manufacturer" "Murata"
			(at 236.22 136.525 0)
			(effects
				(font
					(size 1.27 1.27)
					(thickness 0.15)
				)
				(justify left bottom)
				(hide yes)
			)
		)
		(property "MPN" "GRM155R61H104KE14D"
			(at 236.22 133.985 0)
			(effects
				(font
					(size 1.27 1.27)
					(thickness 0.15)
				)
				(justify left bottom)
				(hide yes)
			)
		)
		(property "Val" "100n"
			(at 250.825 114.935 0)
			(effects
				(font
					(size 1.27 1.27)
					(thickness 0.15)
				)
			)
		)
		(property "License" "Apache-2.0"
			(at 236.22 139.065 0)
			(effects
				(font
					(size 1.27 1.27)
					(thickness 0.15)
				)
				(justify left bottom)
				(hide yes)
			)
		)
		(property "Author" "Antmicro"
			(at 236.22 141.605 0)
			(effects
				(font
					(size 1.27 1.27)
					(thickness 0.15)
				)
				(justify left bottom)
				(hide yes)
			)
		)
		(property "Voltage" "50V"
			(at 236.22 144.145 0)
			(effects
				(font
					(size 1.27 1.27)
				)
				(justify left bottom)
				(hide yes)
			)
		)
		(property "Dielectric" "X5R"
			(at 236.22 146.685 0)
			(effects
				(font
					(size 1.27 1.27)
				)
				(justify left bottom)
				(hide yes)
			)
		)
		(pin "1"
		)
		(pin "2"
		)
		(instances
			(project "sodimm-ddr5-tester"
				(path ""
					(reference "C227")
					(unit 1)
				)
			)
		)
	)
	(symbol
		(lib_id "antmicroCapacitors0402:C_100n_0402")
		(at 256.54 168.275 0)
		(mirror y)
		(unit 1)
		(exclude_from_sim no)
		(in_bom yes)
		(on_board yes)
		(dnp no)
		(property "Reference" "C222"
			(at 257.81 167.005 0)
			(effects
				(font
					(size 1.27 1.27)
				)
			)
		)
		(property "Value" "C_100n_0402"
			(at 236.22 178.435 0)
			(effects
				(font
					(size 1.27 1.27)
					(thickness 0.15)
				)
				(justify left bottom)
				(hide yes)
			)
		)
		(property "Footprint" "antmicro-footprints:C_0402_1005Metric"
			(at 236.22 180.975 0)
			(effects
				(font
					(size 1.27 1.27)
					(thickness 0.15)
				)
				(justify left bottom)
				(hide yes)
			)
		)
		(property "Datasheet" "https://www.murata.com/products/productdetail?partno=GRM155R61H104KE14%23"
			(at 236.22 183.515 0)
			(effects
				(font
					(size 1.27 1.27)
					(thickness 0.15)
				)
				(justify left bottom)
				(hide yes)
			)
		)
		(property "Description" ""
			(at 256.54 168.275 0)
			(effects
				(font
					(size 1.27 1.27)
				)
			)
		)
		(property "Manufacturer" "Murata"
			(at 236.22 188.595 0)
			(effects
				(font
					(size 1.27 1.27)
					(thickness 0.15)
				)
				(justify left bottom)
				(hide yes)
			)
		)
		(property "MPN" "GRM155R61H104KE14D"
			(at 236.22 186.055 0)
			(effects
				(font
					(size 1.27 1.27)
					(thickness 0.15)
				)
				(justify left bottom)
				(hide yes)
			)
		)
		(property "Val" "100n"
			(at 250.825 167.005 0)
			(effects
				(font
					(size 1.27 1.27)
					(thickness 0.15)
				)
			)
		)
		(property "License" "Apache-2.0"
			(at 236.22 191.135 0)
			(effects
				(font
					(size 1.27 1.27)
					(thickness 0.15)
				)
				(justify left bottom)
				(hide yes)
			)
		)
		(property "Author" "Antmicro"
			(at 236.22 193.675 0)
			(effects
				(font
					(size 1.27 1.27)
					(thickness 0.15)
				)
				(justify left bottom)
				(hide yes)
			)
		)
		(property "Voltage" "50V"
			(at 236.22 196.215 0)
			(effects
				(font
					(size 1.27 1.27)
				)
				(justify left bottom)
				(hide yes)
			)
		)
		(property "Dielectric" "X5R"
			(at 236.22 198.755 0)
			(effects
				(font
					(size 1.27 1.27)
				)
				(justify left bottom)
				(hide yes)
			)
		)
		(pin "1"
		)
		(pin "2"
		)
		(instances
			(project "sodimm-ddr5-tester"
				(path ""
					(reference "C222")
					(unit 1)
				)
			)
		)
	)
	(symbol
		(lib_id "antmicroCapacitors0402:C_100n_0402")
		(at 256.54 125.73 0)
		(mirror y)
		(unit 1)
		(exclude_from_sim no)
		(in_bom yes)
		(on_board yes)
		(dnp no)
		(property "Reference" "C228"
			(at 257.81 124.46 0)
			(effects
				(font
					(size 1.27 1.27)
				)
			)
		)
		(property "Value" "C_100n_0402"
			(at 236.22 135.89 0)
			(effects
				(font
					(size 1.27 1.27)
					(thickness 0.15)
				)
				(justify left bottom)
				(hide yes)
			)
		)
		(property "Footprint" "antmicro-footprints:C_0402_1005Metric"
			(at 236.22 138.43 0)
			(effects
				(font
					(size 1.27 1.27)
					(thickness 0.15)
				)
				(justify left bottom)
				(hide yes)
			)
		)
		(property "Datasheet" "https://www.murata.com/products/productdetail?partno=GRM155R61H104KE14%23"
			(at 236.22 140.97 0)
			(effects
				(font
					(size 1.27 1.27)
					(thickness 0.15)
				)
				(justify left bottom)
				(hide yes)
			)
		)
		(property "Description" ""
			(at 256.54 125.73 0)
			(effects
				(font
					(size 1.27 1.27)
				)
			)
		)
		(property "Manufacturer" "Murata"
			(at 236.22 146.05 0)
			(effects
				(font
					(size 1.27 1.27)
					(thickness 0.15)
				)
				(justify left bottom)
				(hide yes)
			)
		)
		(property "MPN" "GRM155R61H104KE14D"
			(at 236.22 143.51 0)
			(effects
				(font
					(size 1.27 1.27)
					(thickness 0.15)
				)
				(justify left bottom)
				(hide yes)
			)
		)
		(property "Val" "100n"
			(at 250.825 124.46 0)
			(effects
				(font
					(size 1.27 1.27)
					(thickness 0.15)
				)
			)
		)
		(property "License" "Apache-2.0"
			(at 236.22 148.59 0)
			(effects
				(font
					(size 1.27 1.27)
					(thickness 0.15)
				)
				(justify left bottom)
				(hide yes)
			)
		)
		(property "Author" "Antmicro"
			(at 236.22 151.13 0)
			(effects
				(font
					(size 1.27 1.27)
					(thickness 0.15)
				)
				(justify left bottom)
				(hide yes)
			)
		)
		(property "Voltage" "50V"
			(at 236.22 153.67 0)
			(effects
				(font
					(size 1.27 1.27)
				)
				(justify left bottom)
				(hide yes)
			)
		)
		(property "Dielectric" "X5R"
			(at 236.22 156.21 0)
			(effects
				(font
					(size 1.27 1.27)
				)
				(justify left bottom)
				(hide yes)
			)
		)
		(pin "1"
		)
		(pin "2"
		)
		(instances
			(project "sodimm-ddr5-tester"
				(path ""
					(reference "C228")
					(unit 1)
				)
			)
		)
	)
	(symbol
		(lib_id "antmicroCapacitors0402:C_100n_0402")
		(at 256.54 140.335 0)
		(mirror y)
		(unit 1)
		(exclude_from_sim no)
		(in_bom yes)
		(on_board yes)
		(dnp no)
		(property "Reference" "C232"
			(at 257.81 139.065 0)
			(effects
				(font
					(size 1.27 1.27)
				)
			)
		)
		(property "Value" "C_100n_0402"
			(at 236.22 150.495 0)
			(effects
				(font
					(size 1.27 1.27)
					(thickness 0.15)
				)
				(justify left bottom)
				(hide yes)
			)
		)
		(property "Footprint" "antmicro-footprints:C_0402_1005Metric"
			(at 236.22 153.035 0)
			(effects
				(font
					(size 1.27 1.27)
					(thickness 0.15)
				)
				(justify left bottom)
				(hide yes)
			)
		)
		(property "Datasheet" "https://www.murata.com/products/productdetail?partno=GRM155R61H104KE14%23"
			(at 236.22 155.575 0)
			(effects
				(font
					(size 1.27 1.27)
					(thickness 0.15)
				)
				(justify left bottom)
				(hide yes)
			)
		)
		(property "Description" ""
			(at 256.54 140.335 0)
			(effects
				(font
					(size 1.27 1.27)
				)
			)
		)
		(property "Manufacturer" "Murata"
			(at 236.22 160.655 0)
			(effects
				(font
					(size 1.27 1.27)
					(thickness 0.15)
				)
				(justify left bottom)
				(hide yes)
			)
		)
		(property "MPN" "GRM155R61H104KE14D"
			(at 236.22 158.115 0)
			(effects
				(font
					(size 1.27 1.27)
					(thickness 0.15)
				)
				(justify left bottom)
				(hide yes)
			)
		)
		(property "Val" "100n"
			(at 250.825 139.065 0)
			(effects
				(font
					(size 1.27 1.27)
					(thickness 0.15)
				)
			)
		)
		(property "License" "Apache-2.0"
			(at 236.22 163.195 0)
			(effects
				(font
					(size 1.27 1.27)
					(thickness 0.15)
				)
				(justify left bottom)
				(hide yes)
			)
		)
		(property "Author" "Antmicro"
			(at 236.22 165.735 0)
			(effects
				(font
					(size 1.27 1.27)
					(thickness 0.15)
				)
				(justify left bottom)
				(hide yes)
			)
		)
		(property "Voltage" "50V"
			(at 236.22 168.275 0)
			(effects
				(font
					(size 1.27 1.27)
				)
				(justify left bottom)
				(hide yes)
			)
		)
		(property "Dielectric" "X5R"
			(at 236.22 170.815 0)
			(effects
				(font
					(size 1.27 1.27)
				)
				(justify left bottom)
				(hide yes)
			)
		)
		(pin "1"
		)
		(pin "2"
		)
		(instances
			(project "sodimm-ddr5-tester"
				(path ""
					(reference "C232")
					(unit 1)
				)
			)
		)
	)
	(symbol
		(lib_id "antmicroCapacitors0402:C_100n_0402")
		(at 256.54 106.045 0)
		(mirror y)
		(unit 1)
		(exclude_from_sim no)
		(in_bom yes)
		(on_board yes)
		(dnp no)
		(property "Reference" "C226"
			(at 257.81 104.775 0)
			(effects
				(font
					(size 1.27 1.27)
				)
			)
		)
		(property "Value" "C_100n_0402"
			(at 236.22 116.205 0)
			(effects
				(font
					(size 1.27 1.27)
					(thickness 0.15)
				)
				(justify left bottom)
				(hide yes)
			)
		)
		(property "Footprint" "antmicro-footprints:C_0402_1005Metric"
			(at 236.22 118.745 0)
			(effects
				(font
					(size 1.27 1.27)
					(thickness 0.15)
				)
				(justify left bottom)
				(hide yes)
			)
		)
		(property "Datasheet" "https://www.murata.com/products/productdetail?partno=GRM155R61H104KE14%23"
			(at 236.22 121.285 0)
			(effects
				(font
					(size 1.27 1.27)
					(thickness 0.15)
				)
				(justify left bottom)
				(hide yes)
			)
		)
		(property "Description" ""
			(at 256.54 106.045 0)
			(effects
				(font
					(size 1.27 1.27)
				)
			)
		)
		(property "Manufacturer" "Murata"
			(at 236.22 126.365 0)
			(effects
				(font
					(size 1.27 1.27)
					(thickness 0.15)
				)
				(justify left bottom)
				(hide yes)
			)
		)
		(property "MPN" "GRM155R61H104KE14D"
			(at 236.22 123.825 0)
			(effects
				(font
					(size 1.27 1.27)
					(thickness 0.15)
				)
				(justify left bottom)
				(hide yes)
			)
		)
		(property "Val" "100n"
			(at 250.825 104.775 0)
			(effects
				(font
					(size 1.27 1.27)
					(thickness 0.15)
				)
			)
		)
		(property "License" "Apache-2.0"
			(at 236.22 128.905 0)
			(effects
				(font
					(size 1.27 1.27)
					(thickness 0.15)
				)
				(justify left bottom)
				(hide yes)
			)
		)
		(property "Author" "Antmicro"
			(at 236.22 131.445 0)
			(effects
				(font
					(size 1.27 1.27)
					(thickness 0.15)
				)
				(justify left bottom)
				(hide yes)
			)
		)
		(property "Voltage" "50V"
			(at 236.22 133.985 0)
			(effects
				(font
					(size 1.27 1.27)
				)
				(justify left bottom)
				(hide yes)
			)
		)
		(property "Dielectric" "X5R"
			(at 236.22 136.525 0)
			(effects
				(font
					(size 1.27 1.27)
				)
				(justify left bottom)
				(hide yes)
			)
		)
		(pin "1"
		)
		(pin "2"
		)
		(instances
			(project "sodimm-ddr5-tester"
				(path ""
					(reference "C226")
					(unit 1)
				)
			)
		)
	)
	(symbol
		(lib_id "antmicroCapacitors0402:C_100n_0402")
		(at 256.54 111.125 0)
		(mirror y)
		(unit 1)
		(exclude_from_sim no)
		(in_bom yes)
		(on_board yes)
		(dnp no)
		(property "Reference" "C230"
			(at 257.81 109.855 0)
			(effects
				(font
					(size 1.27 1.27)
				)
			)
		)
		(property "Value" "C_100n_0402"
			(at 236.22 121.285 0)
			(effects
				(font
					(size 1.27 1.27)
					(thickness 0.15)
				)
				(justify left bottom)
				(hide yes)
			)
		)
		(property "Footprint" "antmicro-footprints:C_0402_1005Metric"
			(at 236.22 123.825 0)
			(effects
				(font
					(size 1.27 1.27)
					(thickness 0.15)
				)
				(justify left bottom)
				(hide yes)
			)
		)
		(property "Datasheet" "https://www.murata.com/products/productdetail?partno=GRM155R61H104KE14%23"
			(at 236.22 126.365 0)
			(effects
				(font
					(size 1.27 1.27)
					(thickness 0.15)
				)
				(justify left bottom)
				(hide yes)
			)
		)
		(property "Description" ""
			(at 256.54 111.125 0)
			(effects
				(font
					(size 1.27 1.27)
				)
			)
		)
		(property "Manufacturer" "Murata"
			(at 236.22 131.445 0)
			(effects
				(font
					(size 1.27 1.27)
					(thickness 0.15)
				)
				(justify left bottom)
				(hide yes)
			)
		)
		(property "MPN" "GRM155R61H104KE14D"
			(at 236.22 128.905 0)
			(effects
				(font
					(size 1.27 1.27)
					(thickness 0.15)
				)
				(justify left bottom)
				(hide yes)
			)
		)
		(property "Val" "100n"
			(at 250.825 109.855 0)
			(effects
				(font
					(size 1.27 1.27)
					(thickness 0.15)
				)
			)
		)
		(property "License" "Apache-2.0"
			(at 236.22 133.985 0)
			(effects
				(font
					(size 1.27 1.27)
					(thickness 0.15)
				)
				(justify left bottom)
				(hide yes)
			)
		)
		(property "Author" "Antmicro"
			(at 236.22 136.525 0)
			(effects
				(font
					(size 1.27 1.27)
					(thickness 0.15)
				)
				(justify left bottom)
				(hide yes)
			)
		)
		(property "Voltage" "50V"
			(at 236.22 139.065 0)
			(effects
				(font
					(size 1.27 1.27)
				)
				(justify left bottom)
				(hide yes)
			)
		)
		(property "Dielectric" "X5R"
			(at 236.22 141.605 0)
			(effects
				(font
					(size 1.27 1.27)
				)
				(justify left bottom)
				(hide yes)
			)
		)
		(pin "1"
		)
		(pin "2"
		)
		(instances
			(project "sodimm-ddr5-tester"
				(path ""
					(reference "C230")
					(unit 1)
				)
			)
		)
	)
	(symbol
		(lib_id "antmicroCapacitors0402:C_100n_0402")
		(at 251.46 130.81 0)
		(mirror x)
		(unit 1)
		(exclude_from_sim no)
		(in_bom yes)
		(on_board yes)
		(dnp no)
		(property "Reference" "C233"
			(at 257.81 129.54 0)
			(effects
				(font
					(size 1.27 1.27)
				)
			)
		)
		(property "Value" "C_100n_0402"
			(at 271.78 120.65 0)
			(effects
				(font
					(size 1.27 1.27)
					(thickness 0.15)
				)
				(justify left bottom)
				(hide yes)
			)
		)
		(property "Footprint" "antmicro-footprints:C_0402_1005Metric"
			(at 271.78 118.11 0)
			(effects
				(font
					(size 1.27 1.27)
					(thickness 0.15)
				)
				(justify left bottom)
				(hide yes)
			)
		)
		(property "Datasheet" "https://www.murata.com/products/productdetail?partno=GRM155R61H104KE14%23"
			(at 271.78 115.57 0)
			(effects
				(font
					(size 1.27 1.27)
					(thickness 0.15)
				)
				(justify left bottom)
				(hide yes)
			)
		)
		(property "Description" ""
			(at 251.46 130.81 0)
			(effects
				(font
					(size 1.27 1.27)
				)
			)
		)
		(property "Manufacturer" "Murata"
			(at 271.78 110.49 0)
			(effects
				(font
					(size 1.27 1.27)
					(thickness 0.15)
				)
				(justify left bottom)
				(hide yes)
			)
		)
		(property "MPN" "GRM155R61H104KE14D"
			(at 271.78 113.03 0)
			(effects
				(font
					(size 1.27 1.27)
					(thickness 0.15)
				)
				(justify left bottom)
				(hide yes)
			)
		)
		(property "Val" "100n"
			(at 250.825 129.54 0)
			(effects
				(font
					(size 1.27 1.27)
					(thickness 0.15)
				)
			)
		)
		(property "License" "Apache-2.0"
			(at 271.78 107.95 0)
			(effects
				(font
					(size 1.27 1.27)
					(thickness 0.15)
				)
				(justify left bottom)
				(hide yes)
			)
		)
		(property "Author" "Antmicro"
			(at 271.78 105.41 0)
			(effects
				(font
					(size 1.27 1.27)
					(thickness 0.15)
				)
				(justify left bottom)
				(hide yes)
			)
		)
		(property "Voltage" "50V"
			(at 271.78 102.87 0)
			(effects
				(font
					(size 1.27 1.27)
				)
				(justify left bottom)
				(hide yes)
			)
		)
		(property "Dielectric" "X5R"
			(at 271.78 100.33 0)
			(effects
				(font
					(size 1.27 1.27)
				)
				(justify left bottom)
				(hide yes)
			)
		)
		(pin "1"
		)
		(pin "2"
		)
		(instances
			(project "sodimm-ddr5-tester"
				(path ""
					(reference "C233")
					(unit 1)
				)
			)
		)
	)
	(symbol
		(lib_id "antmicroFPGAChips:XC7K160T-FFG676")
		(at 131.445 109.855 0)
		(unit 9)
		(exclude_from_sim no)
		(in_bom yes)
		(on_board yes)
		(dnp no)
		(fields_autoplaced yes)
		(property "Reference" "U4"
			(at 158.75 99.8134 0)
			(effects
				(font
					(size 1.27 1.27)
				)
			)
		)
		(property "Value" "XC7K160T-FFG676"
			(at 158.75 102.3437 0)
			(effects
				(font
					(size 1.27 1.27)
					(thickness 0.15)
				)
			)
		)
		(property "Footprint" "antmicro-footprints:BGA-676_27x27mm_Layout26x26_P1x1mm_FFG676"
			(at 200.025 112.395 0)
			(effects
				(font
					(size 1.27 1.27)
					(thickness 0.15)
				)
				(justify left bottom)
				(hide yes)
			)
		)
		(property "Datasheet" "https://docs.xilinx.com/v/u/en-US/ds180_7Series_Overview"
			(at 200.025 114.935 0)
			(effects
				(font
					(size 1.27 1.27)
					(thickness 0.15)
				)
				(justify left bottom)
				(hide yes)
			)
		)
		(property "Description" ""
			(at 131.445 109.855 0)
			(effects
				(font
					(size 1.27 1.27)
				)
			)
		)
		(property "MPN" "XC7K160T-FFG676"
			(at 131.445 109.855 0)
			(effects
				(font
					(size 1.27 1.27)
				)
				(hide yes)
			)
		)
		(property "Author" "Antmicro"
			(at 200.025 117.475 0)
			(effects
				(font
					(size 1.27 1.27)
					(thickness 0.15)
				)
				(justify left bottom)
				(hide yes)
			)
		)
		(property "License" "Apache-2.0"
			(at 200.025 120.015 0)
			(effects
				(font
					(size 1.27 1.27)
					(thickness 0.15)
				)
				(justify left bottom)
				(hide yes)
			)
		)
		(property "Manufacturer" "AMD-Xilinx"
			(at 131.445 109.855 0)
			(effects
				(font
					(size 1.27 1.27)
				)
				(hide yes)
			)
		)
		(pin "AA21"
		)
		(pin "AA22"
		)
		(pin "AA23"
		)
		(pin "AA24"
		)
		(pin "AA25"
		)
		(pin "AB21"
		)
		(pin "AB22"
		)
		(pin "AB24"
		)
		(pin "AB25"
		)
		(pin "AB26"
		)
		(pin "AC21"
		)
		(pin "AC22"
		)
		(pin "AC23"
		)
		(pin "AC24"
		)
		(pin "AC25"
		)
		(pin "AC26"
		)
		(pin "AD21"
		)
		(pin "AD22"
		)
		(pin "AD23"
		)
		(pin "AD24"
		)
		(pin "AD25"
		)
		(pin "AD26"
		)
		(pin "AE21"
		)
		(pin "AE22"
		)
		(pin "AE23"
		)
		(pin "AE25"
		)
		(pin "AE26"
		)
		(pin "AF22"
		)
		(pin "AF23"
		)
		(pin "AF24"
		)
		(pin "AF25"
		)
		(pin "AF26"
		)
		(pin "U21"
		)
		(pin "U22"
		)
		(pin "U23"
		)
		(pin "U24"
		)
		(pin "U25"
		)
		(pin "U26"
		)
		(pin "V20"
		)
		(pin "V21"
		)
		(pin "V22"
		)
		(pin "V23"
		)
		(pin "V24"
		)
		(pin "V26"
		)
		(pin "W20"
		)
		(pin "W21"
		)
		(pin "W23"
		)
		(pin "W24"
		)
		(pin "W25"
		)
		(pin "W26"
		)
		(pin "Y20"
		)
		(pin "Y21"
		)
		(pin "Y22"
		)
		(pin "Y23"
		)
		(pin "Y24"
		)
		(pin "Y25"
		)
		(pin "Y26"
		)
		(pin "K24"
		)
		(pin "K25"
		)
		(pin "K26"
		)
		(pin "L24"
		)
		(pin "L25"
		)
		(pin "M19"
		)
		(pin "M20"
		)
		(pin "M21"
		)
		(pin "M22"
		)
		(pin "M24"
		)
		(pin "M25"
		)
		(pin "M26"
		)
		(pin "N16"
		)
		(pin "N17"
		)
		(pin "N18"
		)
		(pin "N19"
		)
		(pin "N21"
		)
		(pin "N22"
		)
		(pin "N23"
		)
		(pin "N24"
		)
		(pin "N25"
		)
		(pin "N26"
		)
		(pin "P16"
		)
		(pin "P18"
		)
		(pin "P19"
		)
		(pin "P20"
		)
		(pin "P21"
		)
		(pin "P22"
		)
		(pin "P23"
		)
		(pin "P24"
		)
		(pin "P25"
		)
		(pin "P26"
		)
		(pin "R16"
		)
		(pin "R17"
		)
		(pin "R18"
		)
		(pin "R19"
		)
		(pin "R20"
		)
		(pin "R21"
		)
		(pin "R22"
		)
		(pin "R23"
		)
		(pin "R25"
		)
		(pin "R26"
		)
		(pin "T16"
		)
		(pin "T17"
		)
		(pin "T18"
		)
		(pin "T19"
		)
		(pin "T20"
		)
		(pin "T22"
		)
		(pin "T23"
		)
		(pin "T24"
		)
		(pin "T25"
		)
		(pin "T26"
		)
		(pin "U16"
		)
		(pin "U17"
		)
		(pin "U19"
		)
		(pin "U20"
		)
		(pin "A20"
		)
		(pin "A21"
		)
		(pin "A22"
		)
		(pin "A23"
		)
		(pin "A24"
		)
		(pin "A25"
		)
		(pin "B20"
		)
		(pin "B21"
		)
		(pin "B22"
		)
		(pin "B24"
		)
		(pin "B25"
		)
		(pin "B26"
		)
		(pin "C21"
		)
		(pin "C22"
		)
		(pin "C23"
		)
		(pin "C24"
		)
		(pin "C25"
		)
		(pin "C26"
		)
		(pin "D21"
		)
		(pin "D22"
		)
		(pin "D23"
		)
		(pin "D24"
		)
		(pin "D25"
		)
		(pin "D26"
		)
		(pin "E21"
		)
		(pin "E22"
		)
		(pin "E23"
		)
		(pin "E25"
		)
		(pin "E26"
		)
		(pin "F22"
		)
		(pin "F23"
		)
		(pin "F24"
		)
		(pin "F25"
		)
		(pin "F26"
		)
		(pin "G21"
		)
		(pin "G22"
		)
		(pin "G23"
		)
		(pin "G24"
		)
		(pin "G25"
		)
		(pin "G26"
		)
		(pin "H21"
		)
		(pin "H22"
		)
		(pin "H23"
		)
		(pin "H24"
		)
		(pin "H26"
		)
		(pin "J21"
		)
		(pin "J23"
		)
		(pin "J24"
		)
		(pin "J25"
		)
		(pin "J26"
		)
		(pin "K21"
		)
		(pin "K22"
		)
		(pin "K23"
		)
		(pin "L21"
		)
		(pin "L22"
		)
		(pin "L23"
		)
		(pin "A17"
		)
		(pin "A18"
		)
		(pin "A19"
		)
		(pin "B16"
		)
		(pin "B17"
		)
		(pin "B18"
		)
		(pin "B19"
		)
		(pin "C16"
		)
		(pin "C17"
		)
		(pin "C18"
		)
		(pin "C19"
		)
		(pin "D15"
		)
		(pin "D16"
		)
		(pin "D18"
		)
		(pin "D19"
		)
		(pin "D20"
		)
		(pin "E15"
		)
		(pin "E16"
		)
		(pin "E17"
		)
		(pin "E18"
		)
		(pin "E19"
		)
		(pin "E20"
		)
		(pin "F15"
		)
		(pin "F16"
		)
		(pin "F17"
		)
		(pin "F18"
		)
		(pin "F19"
		)
		(pin "F20"
		)
		(pin "G15"
		)
		(pin "G16"
		)
		(pin "G17"
		)
		(pin "G19"
		)
		(pin "G20"
		)
		(pin "H16"
		)
		(pin "H17"
		)
		(pin "H18"
		)
		(pin "H19"
		)
		(pin "H20"
		)
		(pin "J15"
		)
		(pin "J16"
		)
		(pin "J17"
		)
		(pin "J18"
		)
		(pin "J19"
		)
		(pin "J20"
		)
		(pin "K15"
		)
		(pin "K16"
		)
		(pin "K17"
		)
		(pin "K18"
		)
		(pin "K20"
		)
		(pin "L17"
		)
		(pin "L18"
		)
		(pin "L19"
		)
		(pin "L20"
		)
		(pin "M16"
		)
		(pin "M17"
		)
		(pin "M18"
		)
		(pin "A10"
		)
		(pin "A11"
		)
		(pin "A12"
		)
		(pin "A13"
		)
		(pin "A14"
		)
		(pin "A15"
		)
		(pin "A8"
		)
		(pin "A9"
		)
		(pin "B10"
		)
		(pin "B11"
		)
		(pin "B12"
		)
		(pin "B14"
		)
		(pin "B15"
		)
		(pin "B8"
		)
		(pin "B9"
		)
		(pin "C11"
		)
		(pin "C12"
		)
		(pin "C13"
		)
		(pin "C14"
		)
		(pin "C15"
		)
		(pin "C9"
		)
		(pin "D10"
		)
		(pin "D11"
		)
		(pin "D12"
		)
		(pin "D13"
		)
		(pin "D14"
		)
		(pin "D8"
		)
		(pin "D9"
		)
		(pin "E10"
		)
		(pin "E11"
		)
		(pin "E12"
		)
		(pin "E13"
		)
		(pin "E9"
		)
		(pin "F10"
		)
		(pin "F12"
		)
		(pin "F13"
		)
		(pin "F14"
		)
		(pin "F8"
		)
		(pin "F9"
		)
		(pin "G10"
		)
		(pin "G11"
		)
		(pin "G12"
		)
		(pin "G13"
		)
		(pin "G14"
		)
		(pin "G9"
		)
		(pin "H10"
		)
		(pin "H11"
		)
		(pin "H12"
		)
		(pin "H13"
		)
		(pin "H14"
		)
		(pin "H8"
		)
		(pin "H9"
		)
		(pin "J10"
		)
		(pin "J11"
		)
		(pin "J13"
		)
		(pin "J14"
		)
		(pin "J8"
		)
		(pin "AA14"
		)
		(pin "AA15"
		)
		(pin "AA17"
		)
		(pin "AA18"
		)
		(pin "AA19"
		)
		(pin "AA20"
		)
		(pin "AB14"
		)
		(pin "AB15"
		)
		(pin "AB16"
		)
		(pin "AB17"
		)
		(pin "AB18"
		)
		(pin "AB19"
		)
		(pin "AB20"
		)
		(pin "AC14"
		)
		(pin "AC15"
		)
		(pin "AC16"
		)
		(pin "AC17"
		)
		(pin "AC18"
		)
		(pin "AC19"
		)
		(pin "AD14"
		)
		(pin "AD15"
		)
		(pin "AD16"
		)
		(pin "AD18"
		)
		(pin "AD19"
		)
		(pin "AD20"
		)
		(pin "AE15"
		)
		(pin "AE16"
		)
		(pin "AE17"
		)
		(pin "AE18"
		)
		(pin "AE19"
		)
		(pin "AE20"
		)
		(pin "AF14"
		)
		(pin "AF15"
		)
		(pin "AF16"
		)
		(pin "AF17"
		)
		(pin "AF18"
		)
		(pin "AF19"
		)
		(pin "AF20"
		)
		(pin "V13"
		)
		(pin "V14"
		)
		(pin "V16"
		)
		(pin "V17"
		)
		(pin "V18"
		)
		(pin "V19"
		)
		(pin "W13"
		)
		(pin "W14"
		)
		(pin "W15"
		)
		(pin "W16"
		)
		(pin "W17"
		)
		(pin "W18"
		)
		(pin "W19"
		)
		(pin "Y14"
		)
		(pin "Y15"
		)
		(pin "Y16"
		)
		(pin "Y17"
		)
		(pin "Y18"
		)
		(pin "AA10"
		)
		(pin "AA11"
		)
		(pin "AA12"
		)
		(pin "AA13"
		)
		(pin "AA7"
		)
		(pin "AA8"
		)
		(pin "AA9"
		)
		(pin "AB10"
		)
		(pin "AB11"
		)
		(pin "AB12"
		)
		(pin "AB7"
		)
		(pin "AB8"
		)
		(pin "AB9"
		)
		(pin "AC11"
		)
		(pin "AC12"
		)
		(pin "AC13"
		)
		(pin "AC7"
		)
		(pin "AC8"
		)
		(pin "AC9"
		)
		(pin "AD10"
		)
		(pin "AD11"
		)
		(pin "AD12"
		)
		(pin "AD13"
		)
		(pin "AD8"
		)
		(pin "AD9"
		)
		(pin "AE10"
		)
		(pin "AE11"
		)
		(pin "AE12"
		)
		(pin "AE13"
		)
		(pin "AE7"
		)
		(pin "AE8"
		)
		(pin "AE9"
		)
		(pin "AF10"
		)
		(pin "AF12"
		)
		(pin "AF13"
		)
		(pin "AF7"
		)
		(pin "AF8"
		)
		(pin "AF9"
		)
		(pin "U9"
		)
		(pin "V10"
		)
		(pin "V11"
		)
		(pin "V12"
		)
		(pin "V7"
		)
		(pin "V8"
		)
		(pin "V9"
		)
		(pin "W10"
		)
		(pin "W11"
		)
		(pin "W7"
		)
		(pin "W8"
		)
		(pin "W9"
		)
		(pin "Y10"
		)
		(pin "Y11"
		)
		(pin "Y12"
		)
		(pin "Y13"
		)
		(pin "Y7"
		)
		(pin "Y8"
		)
		(pin "AA1"
		)
		(pin "AA2"
		)
		(pin "AA3"
		)
		(pin "AA4"
		)
		(pin "AA5"
		)
		(pin "AB1"
		)
		(pin "AB2"
		)
		(pin "AB4"
		)
		(pin "AB5"
		)
		(pin "AB6"
		)
		(pin "AC1"
		)
		(pin "AC2"
		)
		(pin "AC3"
		)
		(pin "AC4"
		)
		(pin "AC5"
		)
		(pin "AC6"
		)
		(pin "AD1"
		)
		(pin "AD2"
		)
		(pin "AD3"
		)
		(pin "AD4"
		)
		(pin "AD5"
		)
		(pin "AD6"
		)
		(pin "AE1"
		)
		(pin "AE2"
		)
		(pin "AE3"
		)
		(pin "AE5"
		)
		(pin "AE6"
		)
		(pin "AF2"
		)
		(pin "AF3"
		)
		(pin "AF4"
		)
		(pin "AF5"
		)
		(pin "AF6"
		)
		(pin "T7"
		)
		(pin "U1"
		)
		(pin "U2"
		)
		(pin "U3"
		)
		(pin "U4"
		)
		(pin "U5"
		)
		(pin "U6"
		)
		(pin "U7"
		)
		(pin "V1"
		)
		(pin "V2"
		)
		(pin "V3"
		)
		(pin "V4"
		)
		(pin "V6"
		)
		(pin "W1"
		)
		(pin "W3"
		)
		(pin "W4"
		)
		(pin "W5"
		)
		(pin "W6"
		)
		(pin "Y1"
		)
		(pin "Y2"
		)
		(pin "Y3"
		)
		(pin "Y4"
		)
		(pin "Y5"
		)
		(pin "Y6"
		)
		(pin "A3"
		)
		(pin "A4"
		)
		(pin "B1"
		)
		(pin "B2"
		)
		(pin "B5"
		)
		(pin "B6"
		)
		(pin "C3"
		)
		(pin "C4"
		)
		(pin "D1"
		)
		(pin "D2"
		)
		(pin "D5"
		)
		(pin "D6"
		)
		(pin "E3"
		)
		(pin "E4"
		)
		(pin "F1"
		)
		(pin "F2"
		)
		(pin "F5"
		)
		(pin "F6"
		)
		(pin "G3"
		)
		(pin "G4"
		)
		(pin "H1"
		)
		(pin "H2"
		)
		(pin "H5"
		)
		(pin "H6"
		)
		(pin "J3"
		)
		(pin "J4"
		)
		(pin "K1"
		)
		(pin "K2"
		)
		(pin "K5"
		)
		(pin "K6"
		)
		(pin "L3"
		)
		(pin "L4"
		)
		(pin "M1"
		)
		(pin "M2"
		)
		(pin "N3"
		)
		(pin "N4"
		)
		(pin "P1"
		)
		(pin "P2"
		)
		(pin "R3"
		)
		(pin "R4"
		)
		(pin "A1"
		)
		(pin "A16"
		)
		(pin "A2"
		)
		(pin "A26"
		)
		(pin "A5"
		)
		(pin "A6"
		)
		(pin "A7"
		)
		(pin "AA16"
		)
		(pin "AA26"
		)
		(pin "AA6"
		)
		(pin "AB13"
		)
		(pin "AB23"
		)
		(pin "AB3"
		)
		(pin "AC10"
		)
		(pin "AC20"
		)
		(pin "AD17"
		)
		(pin "AD7"
		)
		(pin "AE14"
		)
		(pin "AE24"
		)
		(pin "AE4"
		)
		(pin "AF1"
		)
		(pin "AF11"
		)
		(pin "AF21"
		)
		(pin "B13"
		)
		(pin "B23"
		)
		(pin "B3"
		)
		(pin "B4"
		)
		(pin "B7"
		)
		(pin "C1"
		)
		(pin "C10"
		)
		(pin "C2"
		)
		(pin "C20"
		)
		(pin "C5"
		)
		(pin "C6"
		)
		(pin "C7"
		)
		(pin "D17"
		)
		(pin "D3"
		)
		(pin "D4"
		)
		(pin "D7"
		)
		(pin "E1"
		)
		(pin "E14"
		)
		(pin "E2"
		)
		(pin "E24"
		)
		(pin "E5"
		)
		(pin "E6"
		)
		(pin "E7"
		)
		(pin "E8"
		)
		(pin "F11"
		)
		(pin "F21"
		)
		(pin "F3"
		)
		(pin "F4"
		)
		(pin "F7"
		)
		(pin "G1"
		)
		(pin "G18"
		)
		(pin "G2"
		)
		(pin "G5"
		)
		(pin "G6"
		)
		(pin "G8"
		)
		(pin "H15"
		)
		(pin "H25"
		)
		(pin "H3"
		)
		(pin "H4"
		)
		(pin "H7"
		)
		(pin "J1"
		)
		(pin "J12"
		)
		(pin "J2"
		)
		(pin "J22"
		)
		(pin "J5"
		)
		(pin "J6"
		)
		(pin "J9"
		)
		(pin "K10"
		)
		(pin "K11"
		)
		(pin "K12"
		)
		(pin "K13"
		)
		(pin "K14"
		)
		(pin "K19"
		)
		(pin "K3"
		)
		(pin "K4"
		)
		(pin "K7"
		)
		(pin "K8"
		)
		(pin "K9"
		)
		(pin "L1"
		)
		(pin "L10"
		)
		(pin "L11"
		)
		(pin "L12"
		)
		(pin "L13"
		)
		(pin "L14"
		)
		(pin "L15"
		)
		(pin "L16"
		)
		(pin "L2"
		)
		(pin "L26"
		)
		(pin "L5"
		)
		(pin "L6"
		)
		(pin "L9"
		)
		(pin "M10"
		)
		(pin "M11"
		)
		(pin "M12"
		)
		(pin "M13"
		)
		(pin "M14"
		)
		(pin "M15"
		)
		(pin "M23"
		)
		(pin "M3"
		)
		(pin "M4"
		)
		(pin "M5"
		)
		(pin "M6"
		)
		(pin "M7"
		)
		(pin "M8"
		)
		(pin "M9"
		)
		(pin "N1"
		)
		(pin "N10"
		)
		(pin "N13"
		)
		(pin "N14"
		)
		(pin "N15"
		)
		(pin "N2"
		)
		(pin "N20"
		)
		(pin "N5"
		)
		(pin "N6"
		)
		(pin "N7"
		)
		(pin "N9"
		)
		(pin "P10"
		)
		(pin "P13"
		)
		(pin "P14"
		)
		(pin "P15"
		)
		(pin "P17"
		)
		(pin "P3"
		)
		(pin "P4"
		)
		(pin "P8"
		)
		(pin "P9"
		)
		(pin "R1"
		)
		(pin "R10"
		)
		(pin "R13"
		)
		(pin "R14"
		)
		(pin "R15"
		)
		(pin "R2"
		)
		(pin "R24"
		)
		(pin "R5"
		)
		(pin "R8"
		)
		(pin "R9"
		)
		(pin "T1"
		)
		(pin "T10"
		)
		(pin "T11"
		)
		(pin "T12"
		)
		(pin "T13"
		)
		(pin "T14"
		)
		(pin "T15"
		)
		(pin "T21"
		)
		(pin "T3"
		)
		(pin "T4"
		)
		(pin "T8"
		)
		(pin "T9"
		)
		(pin "U10"
		)
		(pin "U11"
		)
		(pin "U12"
		)
		(pin "U13"
		)
		(pin "U14"
		)
		(pin "U15"
		)
		(pin "U18"
		)
		(pin "U8"
		)
		(pin "V15"
		)
		(pin "V25"
		)
		(pin "V5"
		)
		(pin "W12"
		)
		(pin "W2"
		)
		(pin "W22"
		)
		(pin "Y19"
		)
		(pin "Y9"
		)
		(pin "C8"
		)
		(pin "G7"
		)
		(pin "J7"
		)
		(pin "L7"
		)
		(pin "L8"
		)
		(pin "N11"
		)
		(pin "N12"
		)
		(pin "N8"
		)
		(pin "P11"
		)
		(pin "P12"
		)
		(pin "P5"
		)
		(pin "P6"
		)
		(pin "P7"
		)
		(pin "R11"
		)
		(pin "R12"
		)
		(pin "R6"
		)
		(pin "R7"
		)
		(pin "T2"
		)
		(pin "T5"
		)
		(pin "T6"
		)
		(instances
			(project "sodimm-ddr5-tester"
				(path ""
					(reference "U4")
					(unit 9)
				)
			)
		)
	)
	(symbol
		(lib_id "antmicroCapacitors0402:C_100n_0402")
		(at 256.54 135.255 0)
		(mirror y)
		(unit 1)
		(exclude_from_sim no)
		(in_bom yes)
		(on_board yes)
		(dnp no)
		(property "Reference" "C229"
			(at 257.81 133.985 0)
			(effects
				(font
					(size 1.27 1.27)
				)
			)
		)
		(property "Value" "C_100n_0402"
			(at 236.22 145.415 0)
			(effects
				(font
					(size 1.27 1.27)
					(thickness 0.15)
				)
				(justify left bottom)
				(hide yes)
			)
		)
		(property "Footprint" "antmicro-footprints:C_0402_1005Metric"
			(at 236.22 147.955 0)
			(effects
				(font
					(size 1.27 1.27)
					(thickness 0.15)
				)
				(justify left bottom)
				(hide yes)
			)
		)
		(property "Datasheet" "https://www.murata.com/products/productdetail?partno=GRM155R61H104KE14%23"
			(at 236.22 150.495 0)
			(effects
				(font
					(size 1.27 1.27)
					(thickness 0.15)
				)
				(justify left bottom)
				(hide yes)
			)
		)
		(property "Description" ""
			(at 256.54 135.255 0)
			(effects
				(font
					(size 1.27 1.27)
				)
			)
		)
		(property "Manufacturer" "Murata"
			(at 236.22 155.575 0)
			(effects
				(font
					(size 1.27 1.27)
					(thickness 0.15)
				)
				(justify left bottom)
				(hide yes)
			)
		)
		(property "MPN" "GRM155R61H104KE14D"
			(at 236.22 153.035 0)
			(effects
				(font
					(size 1.27 1.27)
					(thickness 0.15)
				)
				(justify left bottom)
				(hide yes)
			)
		)
		(property "Val" "100n"
			(at 250.825 133.985 0)
			(effects
				(font
					(size 1.27 1.27)
					(thickness 0.15)
				)
			)
		)
		(property "License" "Apache-2.0"
			(at 236.22 158.115 0)
			(effects
				(font
					(size 1.27 1.27)
					(thickness 0.15)
				)
				(justify left bottom)
				(hide yes)
			)
		)
		(property "Author" "Antmicro"
			(at 236.22 160.655 0)
			(effects
				(font
					(size 1.27 1.27)
					(thickness 0.15)
				)
				(justify left bottom)
				(hide yes)
			)
		)
		(property "Voltage" "50V"
			(at 236.22 163.195 0)
			(effects
				(font
					(size 1.27 1.27)
				)
				(justify left bottom)
				(hide yes)
			)
		)
		(property "Dielectric" "X5R"
			(at 236.22 165.735 0)
			(effects
				(font
					(size 1.27 1.27)
				)
				(justify left bottom)
				(hide yes)
			)
		)
		(pin "1"
		)
		(pin "2"
		)
		(instances
			(project "sodimm-ddr5-tester"
				(path ""
					(reference "C229")
					(unit 1)
				)
			)
		)
	)
	(symbol
		(lib_id "antmicroCapacitors0402:C_100n_0402")
		(at 256.54 173.355 0)
		(mirror y)
		(unit 1)
		(exclude_from_sim no)
		(in_bom yes)
		(on_board yes)
		(dnp no)
		(property "Reference" "C223"
			(at 257.81 172.085 0)
			(effects
				(font
					(size 1.27 1.27)
				)
			)
		)
		(property "Value" "C_100n_0402"
			(at 236.22 183.515 0)
			(effects
				(font
					(size 1.27 1.27)
					(thickness 0.15)
				)
				(justify left bottom)
				(hide yes)
			)
		)
		(property "Footprint" "antmicro-footprints:C_0402_1005Metric"
			(at 236.22 186.055 0)
			(effects
				(font
					(size 1.27 1.27)
					(thickness 0.15)
				)
				(justify left bottom)
				(hide yes)
			)
		)
		(property "Datasheet" "https://www.murata.com/products/productdetail?partno=GRM155R61H104KE14%23"
			(at 236.22 188.595 0)
			(effects
				(font
					(size 1.27 1.27)
					(thickness 0.15)
				)
				(justify left bottom)
				(hide yes)
			)
		)
		(property "Description" ""
			(at 256.54 173.355 0)
			(effects
				(font
					(size 1.27 1.27)
				)
			)
		)
		(property "Manufacturer" "Murata"
			(at 236.22 193.675 0)
			(effects
				(font
					(size 1.27 1.27)
					(thickness 0.15)
				)
				(justify left bottom)
				(hide yes)
			)
		)
		(property "MPN" "GRM155R61H104KE14D"
			(at 236.22 191.135 0)
			(effects
				(font
					(size 1.27 1.27)
					(thickness 0.15)
				)
				(justify left bottom)
				(hide yes)
			)
		)
		(property "Val" "100n"
			(at 250.825 172.085 0)
			(effects
				(font
					(size 1.27 1.27)
					(thickness 0.15)
				)
			)
		)
		(property "License" "Apache-2.0"
			(at 236.22 196.215 0)
			(effects
				(font
					(size 1.27 1.27)
					(thickness 0.15)
				)
				(justify left bottom)
				(hide yes)
			)
		)
		(property "Author" "Antmicro"
			(at 236.22 198.755 0)
			(effects
				(font
					(size 1.27 1.27)
					(thickness 0.15)
				)
				(justify left bottom)
				(hide yes)
			)
		)
		(property "Voltage" "50V"
			(at 236.22 201.295 0)
			(effects
				(font
					(size 1.27 1.27)
				)
				(justify left bottom)
				(hide yes)
			)
		)
		(property "Dielectric" "X5R"
			(at 236.22 203.835 0)
			(effects
				(font
					(size 1.27 1.27)
				)
				(justify left bottom)
				(hide yes)
			)
		)
		(pin "1"
		)
		(pin "2"
		)
		(instances
			(project "sodimm-ddr5-tester"
				(path ""
					(reference "C223")
					(unit 1)
				)
			)
		)
	)
	(symbol
		(lib_id "antmicroCapacitors0402:C_100n_0402")
		(at 256.54 121.285 0)
		(mirror y)
		(unit 1)
		(exclude_from_sim no)
		(in_bom yes)
		(on_board yes)
		(dnp no)
		(property "Reference" "C231"
			(at 257.81 120.015 0)
			(effects
				(font
					(size 1.27 1.27)
				)
			)
		)
		(property "Value" "C_100n_0402"
			(at 236.22 131.445 0)
			(effects
				(font
					(size 1.27 1.27)
					(thickness 0.15)
				)
				(justify left bottom)
				(hide yes)
			)
		)
		(property "Footprint" "antmicro-footprints:C_0402_1005Metric"
			(at 236.22 133.985 0)
			(effects
				(font
					(size 1.27 1.27)
					(thickness 0.15)
				)
				(justify left bottom)
				(hide yes)
			)
		)
		(property "Datasheet" "https://www.murata.com/products/productdetail?partno=GRM155R61H104KE14%23"
			(at 236.22 136.525 0)
			(effects
				(font
					(size 1.27 1.27)
					(thickness 0.15)
				)
				(justify left bottom)
				(hide yes)
			)
		)
		(property "Description" ""
			(at 256.54 121.285 0)
			(effects
				(font
					(size 1.27 1.27)
				)
			)
		)
		(property "Manufacturer" "Murata"
			(at 236.22 141.605 0)
			(effects
				(font
					(size 1.27 1.27)
					(thickness 0.15)
				)
				(justify left bottom)
				(hide yes)
			)
		)
		(property "MPN" "GRM155R61H104KE14D"
			(at 236.22 139.065 0)
			(effects
				(font
					(size 1.27 1.27)
					(thickness 0.15)
				)
				(justify left bottom)
				(hide yes)
			)
		)
		(property "Val" "100n"
			(at 250.825 120.015 0)
			(effects
				(font
					(size 1.27 1.27)
					(thickness 0.15)
				)
			)
		)
		(property "License" "Apache-2.0"
			(at 236.22 144.145 0)
			(effects
				(font
					(size 1.27 1.27)
					(thickness 0.15)
				)
				(justify left bottom)
				(hide yes)
			)
		)
		(property "Author" "Antmicro"
			(at 236.22 146.685 0)
			(effects
				(font
					(size 1.27 1.27)
					(thickness 0.15)
				)
				(justify left bottom)
				(hide yes)
			)
		)
		(property "Voltage" "50V"
			(at 236.22 149.225 0)
			(effects
				(font
					(size 1.27 1.27)
				)
				(justify left bottom)
				(hide yes)
			)
		)
		(property "Dielectric" "X5R"
			(at 236.22 151.765 0)
			(effects
				(font
					(size 1.27 1.27)
				)
				(justify left bottom)
				(hide yes)
			)
		)
		(pin "1"
		)
		(pin "2"
		)
		(instances
			(project "sodimm-ddr5-tester"
				(path ""
					(reference "C231")
					(unit 1)
				)
			)
		)
	)
)
